FILE_TYPE=LIBRARY_PARTS;
primitive 'SCONN20_HSU2101L00007H';
  pin
    '1':
      PIN_NUMBER='(1)';
      BIDIRECTIONAL='TRUE';
      INPUT_LOAD='(-0.01,0.01)';
      OUTPUT_LOAD='(1.0,-1.0)';
    '2':
      PIN_NUMBER='(2)';
      BIDIRECTIONAL='TRUE';
      INPUT_LOAD='(-0.01,0.01)';
      OUTPUT_LOAD='(1.0,-1.0)';
    '3':
      PIN_NUMBER='(3)';
      BIDIRECTIONAL='TRUE';
      INPUT_LOAD='(-0.01,0.01)';
      OUTPUT_LOAD='(1.0,-1.0)';
    '4':
      PIN_NUMBER='(4)';
      BIDIRECTIONAL='TRUE';
      INPUT_LOAD='(-0.01,0.01)';
      OUTPUT_LOAD='(1.0,-1.0)';
    '5':
      PIN_NUMBER='(5)';
      BIDIRECTIONAL='TRUE';
      INPUT_LOAD='(-0.01,0.01)';
      OUTPUT_LOAD='(1.0,-1.0)';
    '6':
      PIN_NUMBER='(6)';
      BIDIRECTIONAL='TRUE';
      INPUT_LOAD='(-0.01,0.01)';
      OUTPUT_LOAD='(1.0,-1.0)';
    '7':
      PIN_NUMBER='(7)';
      BIDIRECTIONAL='TRUE';
      INPUT_LOAD='(-0.01,0.01)';
      OUTPUT_LOAD='(1.0,-1.0)';
    '8':
      PIN_NUMBER='(8)';
      BIDIRECTIONAL='TRUE';
      INPUT_LOAD='(-0.01,0.01)';
      OUTPUT_LOAD='(1.0,-1.0)';
    '9':
      PIN_NUMBER='(9)';
      BIDIRECTIONAL='TRUE';
      INPUT_LOAD='(-0.01,0.01)';
      OUTPUT_LOAD='(1.0,-1.0)';
    '10':
      PIN_NUMBER='(10)';
      BIDIRECTIONAL='TRUE';
      INPUT_LOAD='(-0.01,0.01)';
      OUTPUT_LOAD='(1.0,-1.0)';
    '11':
      PIN_NUMBER='(11)';
      BIDIRECTIONAL='TRUE';
      INPUT_LOAD='(-0.01,0.01)';
      OUTPUT_LOAD='(1.0,-1.0)';
    '12':
      PIN_NUMBER='(12)';
      BIDIRECTIONAL='TRUE';
      INPUT_LOAD='(-0.01,0.01)';
      OUTPUT_LOAD='(1.0,-1.0)';
    '13':
      PIN_NUMBER='(13)';
      BIDIRECTIONAL='TRUE';
      INPUT_LOAD='(-0.01,0.01)';
      OUTPUT_LOAD='(1.0,-1.0)';
    '14':
      PIN_NUMBER='(14)';
      BIDIRECTIONAL='TRUE';
      INPUT_LOAD='(-0.01,0.01)';
      OUTPUT_LOAD='(1.0,-1.0)';
    '15':
      PIN_NUMBER='(15)';
      BIDIRECTIONAL='TRUE';
      INPUT_LOAD='(-0.01,0.01)';
      OUTPUT_LOAD='(1.0,-1.0)';
    '16':
      PIN_NUMBER='(16)';
      BIDIRECTIONAL='TRUE';
      INPUT_LOAD='(-0.01,0.01)';
      OUTPUT_LOAD='(1.0,-1.0)';
    '17':
      PIN_NUMBER='(17)';
      BIDIRECTIONAL='TRUE';
      INPUT_LOAD='(-0.01,0.01)';
      OUTPUT_LOAD='(1.0,-1.0)';
    '18':
      PIN_NUMBER='(18)';
      BIDIRECTIONAL='TRUE';
      INPUT_LOAD='(-0.01,0.01)';
      OUTPUT_LOAD='(1.0,-1.0)';
    '19':
      PIN_NUMBER='(19)';
      BIDIRECTIONAL='TRUE';
      INPUT_LOAD='(-0.01,0.01)';
      OUTPUT_LOAD='(1.0,-1.0)';
    '20':
      PIN_NUMBER='(20)';
      BIDIRECTIONAL='TRUE';
      INPUT_LOAD='(-0.01,0.01)';
      OUTPUT_LOAD='(1.0,-1.0)';
  end_pin;
  body
    PART_NAME='SCONN20_HSU2101L00007H';
    BODY_NAME='SCONN20_HSU2101L00007H';
    PHYS_DES_PREFIX='J';
    CLASS='IO';
  end_body;
end_primitive;

END.
